(kicad_pcb
	(version 20241229)
	(generator "pcbnew")
	(generator_version "9.0")
	(general
		(thickness 1.552)
		(legacy_teardrops no)
	)
	(paper "A4")
	(title_block
		(date "2023-07-25")
		(rev "1.1.4")
		(comment 9 "footprints 309-313 of 379")
	)
	(layers
		(0 "F.Cu" signal)
		(4 "In1.Cu" signal)
		(6 "In2.Cu" signal)
		(8 "In3.Cu" signal)
		(10 "In4.Cu" signal)
		(12 "In5.Cu" signal)
		(14 "In6.Cu" signal)
		(2 "B.Cu" signal)
		(9 "F.Adhes" user "F.Adhesive")
		(11 "B.Adhes" user "B.Adhesive")
		(13 "F.Paste" user)
		(15 "B.Paste" user)
		(5 "F.SilkS" user "F.Silkscreen")
		(7 "B.SilkS" user "B.Silkscreen")
		(1 "F.Mask" user)
		(3 "B.Mask" user)
		(17 "Dwgs.User" user "User.Drawings")
		(19 "Cmts.User" user "User.Comments")
		(21 "Eco1.User" user "User.Eco1")
		(23 "Eco2.User" user "User.Eco2")
		(25 "Edge.Cuts" user)
		(27 "Margin" user)
		(31 "F.CrtYd" user "F.Courtyard")
		(29 "B.CrtYd" user "B.Courtyard")
		(35 "F.Fab" user)
		(33 "B.Fab" user)
	)
	(footprint "antmicro-footprints:C_0603_1608Metric"
		(layer "B.Cu")
		(at 118.82 56.14)
		(descr "Capacitor SMD 0603")
		(tags "capacitor 0603")
		(property "Reference" "C8"
			(at -2.59 0.4 0)
			(layer "B.SilkS")
			(effects
				(font
					(size 0.65 0.65)
					(thickness 0.15)
				)
				(justify right bottom mirror)
			)
		)
		(property "Value" "C_22u_0603"
			(at 0 -1.6 0)
			(layer "B.Fab")
			(hide yes)
			(effects
				(font
					(size 0.7 0.7)
					(thickness 0.15)
				)
				(justify right bottom mirror)
			)
		)
		(property "Datasheet" "https://www.murata.com/products/productdetail?partno=GRM188R60J226MEA0%23"
			(at 0 0 0)
			(layer "F.Fab")
			(hide yes)
			(effects
				(font
					(size 1.27 1.27)
					(thickness 0.15)
				)
			)
		)
		(property "Description" "SMD Multilayer Ceramic Capacitor, 22 µF, 6.3 V, 0603 [1608 Metric], ± 20%, X5R, GRM Series"
			(at 0 0 0)
			(layer "F.Fab")
			(hide yes)
			(effects
				(font
					(size 1.27 1.27)
					(thickness 0.15)
				)
			)
		)
		(property "Author" "Antmicro"
			(at 0 0 0)
			(layer "B.Fab")
			(hide yes)
			(effects
				(font
					(size 1 1)
					(thickness 0.15)
				)
				(justify mirror)
			)
		)
		(property "Dielectric" ""
			(at 0 0 0)
			(layer "B.Fab")
			(hide yes)
			(effects
				(font
					(size 1 1)
					(thickness 0.15)
				)
				(justify mirror)
			)
		)
		(property "License" "Apache-2.0"
			(at 0 0 0)
			(layer "B.Fab")
			(hide yes)
			(effects
				(font
					(size 1 1)
					(thickness 0.15)
				)
				(justify mirror)
			)
		)
		(property "MPN" "GRM188R60J226MEA0D"
			(at 0 0 0)
			(layer "B.Fab")
			(hide yes)
			(effects
				(font
					(size 1 1)
					(thickness 0.15)
				)
				(justify mirror)
			)
		)
		(property "Manufacturer" "Murata"
			(at 0 0 0)
			(layer "B.Fab")
			(hide yes)
			(effects
				(font
					(size 1 1)
					(thickness 0.15)
				)
				(justify mirror)
			)
		)
		(property "Val" "22u"
			(at 0 0 0)
			(layer "B.Fab")
			(hide yes)
			(effects
				(font
					(size 1 1)
					(thickness 0.15)
				)
				(justify mirror)
			)
		)
		(property "Voltage" ""
			(at 0 0 0)
			(layer "B.Fab")
			(hide yes)
			(effects
				(font
					(size 1 1)
					(thickness 0.15)
				)
				(justify mirror)
			)
		)
		(sheetname "/Power Supply/")
		(sheetfile "supply.kicad_sch")
		(attr smd)
		(fp_line
			(start -0.15 -0.4)
			(end 0.15 -0.4)
			(stroke
				(width 0.15)
				(type solid)
			)
			(layer "B.SilkS")
		)
		(fp_line
			(start -0.15 0.4)
			(end 0.15 0.4)
			(stroke
				(width 0.15)
				(type solid)
			)
			(layer "B.SilkS")
		)
		(fp_rect
			(start -1.25 0.65)
			(end 1.25 -0.65)
			(stroke
				(width 0.05)
				(type solid)
			)
			(fill no)
			(layer "B.CrtYd")
		)
		(fp_rect
			(start -0.8 0.4)
			(end 0.8 -0.4)
			(stroke
				(width 0.15)
				(type solid)
			)
			(fill no)
			(layer "B.Fab")
		)
		(fp_text user "License: Apache-2.0"
			(at -1.682 -5.895 180)
			(layer "B.Fab")
			(effects
				(font
					(size 0.7 0.7)
					(thickness 0.15)
				)
				(justify left bottom mirror)
			)
		)
		(fp_text user "${REFERENCE}"
			(at -1.682 -3.895 180)
			(layer "B.Fab")
			(effects
				(font
					(size 0.7 0.7)
					(thickness 0.15)
				)
				(justify left bottom mirror)
			)
		)
		(fp_text user "Author: Antmicro"
			(at -1.682 -4.894 180)
			(layer "B.Fab")
			(effects
				(font
					(size 0.7 0.7)
					(thickness 0.15)
				)
				(justify left bottom mirror)
			)
		)
		(pad "1" smd roundrect
			(at -0.7 0)
			(size 0.8 1)
			(layers "B.Cu" "B.Mask" "B.Paste")
			(roundrect_rratio 0.2)
			(net 1 "GND")
			(pintype "passive")
		)
		(pad "2" smd roundrect
			(at 0.7 0)
			(size 0.8 1)
			(layers "B.Cu" "B.Mask" "B.Paste")
			(roundrect_rratio 0.2)
			(net 6 "Vtt")
			(pintype "passive")
		)
	)
	(footprint "antmicro-footprints:C_0201"
		(layer "B.Cu")
		(at 125.1 90.3 180)
		(descr "Capacitor SMD 0201")
		(tags "capacitor SMD 0201")
		(property "Reference" "C85"
			(at 8.67 12.295736 0)
			(layer "B.SilkS")
			(effects
				(font
					(size 0.65 0.65)
					(thickness 0.15)
				)
				(justify left bottom mirror)
			)
		)
		(property "Value" "C_100n_0201"
			(at 0 -1.4 0)
			(layer "B.Fab")
			(hide yes)
			(effects
				(font
					(size 0.7 0.7)
					(thickness 0.15)
				)
				(justify left bottom mirror)
			)
		)
		(property "Datasheet" "https://www.yageo.com/en/Chart/Download/pdf/CC0201KRX6S5BB104"
			(at 0 0 180)
			(layer "F.Fab")
			(hide yes)
			(effects
				(font
					(size 1.27 1.27)
					(thickness 0.15)
				)
			)
		)
		(property "Description" "SMD Multilayer Ceramic Capacitor, 0.1 µF, 6.3 V, 0201 [0603 Metric], ± 10%, X6S, CC Series"
			(at 0 0 180)
			(layer "F.Fab")
			(hide yes)
			(effects
				(font
					(size 1.27 1.27)
					(thickness 0.15)
				)
			)
		)
		(property "Author" "Antmicro"
			(at 250.2 180.6 0)
			(layer "B.Fab")
			(hide yes)
			(effects
				(font
					(size 1 1)
					(thickness 0.15)
				)
				(justify mirror)
			)
		)
		(property "Dielectric" ""
			(at 250.2 180.6 0)
			(layer "B.Fab")
			(hide yes)
			(effects
				(font
					(size 1 1)
					(thickness 0.15)
				)
				(justify mirror)
			)
		)
		(property "License" "Apache-2.0"
			(at 250.2 180.6 0)
			(layer "B.Fab")
			(hide yes)
			(effects
				(font
					(size 1 1)
					(thickness 0.15)
				)
				(justify mirror)
			)
		)
		(property "MPN" "CC0201KRX6S5BB104"
			(at 250.2 180.6 0)
			(layer "B.Fab")
			(hide yes)
			(effects
				(font
					(size 1 1)
					(thickness 0.15)
				)
				(justify mirror)
			)
		)
		(property "Manufacturer" "YAGEO"
			(at 250.2 180.6 0)
			(layer "B.Fab")
			(hide yes)
			(effects
				(font
					(size 1 1)
					(thickness 0.15)
				)
				(justify mirror)
			)
		)
		(property "Val" "100n"
			(at 250.2 180.6 0)
			(layer "B.Fab")
			(hide yes)
			(effects
				(font
					(size 1 1)
					(thickness 0.15)
				)
				(justify mirror)
			)
		)
		(property "Voltage" ""
			(at 250.2 180.6 0)
			(layer "B.Fab")
			(hide yes)
			(effects
				(font
					(size 1 1)
					(thickness 0.15)
				)
				(justify mirror)
			)
		)
		(property "Public" "False"
			(at 0 0 180)
			(unlocked yes)
			(layer "B.Fab")
			(hide yes)
			(effects
				(font
					(size 1 1)
					(thickness 0.15)
				)
				(justify mirror)
			)
		)
		(sheetname "/FPGA Power/")
		(sheetfile "FPGA_Power.kicad_sch")
		(attr smd)
		(fp_rect
			(start -0.7 0.35)
			(end 0.7 -0.35)
			(stroke
				(width 0.05)
				(type default)
			)
			(fill no)
			(layer "B.CrtYd")
		)
		(fp_rect
			(start 0.3 -0.15)
			(end -0.301 0.149)
			(stroke
				(width 0.15)
				(type solid)
			)
			(fill no)
			(layer "B.Fab")
		)
		(fp_text user "Author: Antmicro"
			(at -0.72 -5.4 0)
			(layer "B.Fab")
			(effects
				(font
					(size 0.7 0.7)
					(thickness 0.15)
				)
				(justify left bottom mirror)
			)
		)
		(fp_text user "License: Apache-2.0"
			(at -0.72 -4.4 0)
			(layer "B.Fab")
			(effects
				(font
					(size 0.7 0.7)
					(thickness 0.15)
				)
				(justify left bottom mirror)
			)
		)
		(fp_text user "${REFERENCE}"
			(at -0.72 -3.4 0)
			(layer "B.Fab")
			(effects
				(font
					(size 0.7 0.7)
					(thickness 0.15)
				)
				(justify left bottom mirror)
			)
		)
		(pad "" smd roundrect
			(at -0.349 0.002 180)
			(size 0.318 0.36)
			(layers "B.Paste")
			(roundrect_rratio 0.25)
		)
		(pad "" smd roundrect
			(at 0.341 0.002 180)
			(size 0.318 0.36)
			(layers "B.Paste")
			(roundrect_rratio 0.25)
		)
		(pad "1" smd roundrect
			(at -0.321 0.002 180)
			(size 0.46 0.4)
			(layers "B.Cu" "B.Mask")
			(roundrect_rratio 0.25)
			(net 1 "GND")
			(pintype "passive")
		)
		(pad "2" smd roundrect
			(at 0.32 0.002 180)
			(size 0.46 0.4)
			(layers "B.Cu" "B.Mask")
			(roundrect_rratio 0.25)
			(net 4 "1V0_Power")
			(pintype "passive")
		)
	)
	(footprint "antmicro-footprints:C_0201"
		(layer "B.Cu")
		(at 125.1 85.5 180)
		(descr "Capacitor SMD 0201")
		(tags "capacitor SMD 0201")
		(property "Reference" "C39"
			(at 8.27 12.295736 0)
			(layer "B.SilkS")
			(effects
				(font
					(size 0.65 0.65)
					(thickness 0.15)
				)
				(justify left bottom mirror)
			)
		)
		(property "Value" "C_100n_0201"
			(at 0 -1.4 0)
			(layer "B.Fab")
			(hide yes)
			(effects
				(font
					(size 0.7 0.7)
					(thickness 0.15)
				)
				(justify left bottom mirror)
			)
		)
		(property "Datasheet" "https://www.yageo.com/en/Chart/Download/pdf/CC0201KRX6S5BB104"
			(at 0 0 180)
			(layer "F.Fab")
			(hide yes)
			(effects
				(font
					(size 1.27 1.27)
					(thickness 0.15)
				)
			)
		)
		(property "Description" "SMD Multilayer Ceramic Capacitor, 0.1 µF, 6.3 V, 0201 [0603 Metric], ± 10%, X6S, CC Series"
			(at 0 0 180)
			(layer "F.Fab")
			(hide yes)
			(effects
				(font
					(size 1.27 1.27)
					(thickness 0.15)
				)
			)
		)
		(property "Author" "Antmicro"
			(at 250.2 171 0)
			(layer "B.Fab")
			(hide yes)
			(effects
				(font
					(size 1 1)
					(thickness 0.15)
				)
				(justify mirror)
			)
		)
		(property "Dielectric" ""
			(at 250.2 171 0)
			(layer "B.Fab")
			(hide yes)
			(effects
				(font
					(size 1 1)
					(thickness 0.15)
				)
				(justify mirror)
			)
		)
		(property "License" "Apache-2.0"
			(at 250.2 171 0)
			(layer "B.Fab")
			(hide yes)
			(effects
				(font
					(size 1 1)
					(thickness 0.15)
				)
				(justify mirror)
			)
		)
		(property "MPN" "CC0201KRX6S5BB104"
			(at 250.2 171 0)
			(layer "B.Fab")
			(hide yes)
			(effects
				(font
					(size 1 1)
					(thickness 0.15)
				)
				(justify mirror)
			)
		)
		(property "Manufacturer" "YAGEO"
			(at 250.2 171 0)
			(layer "B.Fab")
			(hide yes)
			(effects
				(font
					(size 1 1)
					(thickness 0.15)
				)
				(justify mirror)
			)
		)
		(property "Val" "100n"
			(at 250.2 171 0)
			(layer "B.Fab")
			(hide yes)
			(effects
				(font
					(size 1 1)
					(thickness 0.15)
				)
				(justify mirror)
			)
		)
		(property "Voltage" ""
			(at 250.2 171 0)
			(layer "B.Fab")
			(hide yes)
			(effects
				(font
					(size 1 1)
					(thickness 0.15)
				)
				(justify mirror)
			)
		)
		(property "Public" "False"
			(at 0 0 180)
			(unlocked yes)
			(layer "B.Fab")
			(hide yes)
			(effects
				(font
					(size 1 1)
					(thickness 0.15)
				)
				(justify mirror)
			)
		)
		(sheetname "/DDR3/")
		(sheetfile "ddr3.kicad_sch")
		(attr smd)
		(fp_rect
			(start -0.7 0.35)
			(end 0.7 -0.35)
			(stroke
				(width 0.05)
				(type default)
			)
			(fill no)
			(layer "B.CrtYd")
		)
		(fp_rect
			(start 0.3 -0.15)
			(end -0.301 0.149)
			(stroke
				(width 0.15)
				(type solid)
			)
			(fill no)
			(layer "B.Fab")
		)
		(fp_text user "${REFERENCE}"
			(at -0.72 -3.4 0)
			(layer "B.Fab")
			(effects
				(font
					(size 0.7 0.7)
					(thickness 0.15)
				)
				(justify left bottom mirror)
			)
		)
		(fp_text user "Author: Antmicro"
			(at -0.72 -5.4 0)
			(layer "B.Fab")
			(effects
				(font
					(size 0.7 0.7)
					(thickness 0.15)
				)
				(justify left bottom mirror)
			)
		)
		(fp_text user "License: Apache-2.0"
			(at -0.72 -4.4 0)
			(layer "B.Fab")
			(effects
				(font
					(size 0.7 0.7)
					(thickness 0.15)
				)
				(justify left bottom mirror)
			)
		)
		(pad "" smd roundrect
			(at -0.349 0.002 180)
			(size 0.318 0.36)
			(layers "B.Paste")
			(roundrect_rratio 0.25)
		)
		(pad "" smd roundrect
			(at 0.341 0.002 180)
			(size 0.318 0.36)
			(layers "B.Paste")
			(roundrect_rratio 0.25)
		)
		(pad "1" smd roundrect
			(at -0.321 0.002 180)
			(size 0.46 0.4)
			(layers "B.Cu" "B.Mask")
			(roundrect_rratio 0.25)
			(net 1 "GND")
			(pintype "passive")
		)
		(pad "2" smd roundrect
			(at 0.32 0.002 180)
			(size 0.46 0.4)
			(layers "B.Cu" "B.Mask")
			(roundrect_rratio 0.25)
			(net 5 "Vref")
			(pintype "passive")
		)
	)
	(footprint "antmicro-footprints:C_0201"
		(layer "B.Cu")
		(at 126.83 92.11 90)
		(descr "Capacitor SMD 0201")
		(tags "capacitor SMD 0201")
		(property "Reference" "C93"
			(at 11.305736 -9 90)
			(layer "B.SilkS")
			(effects
				(font
					(size 0.65 0.65)
					(thickness 0.15)
				)
				(justify right bottom mirror)
			)
		)
		(property "Value" "C_100n_0201"
			(at 0 -1.4 90)
			(layer "B.Fab")
			(hide yes)
			(effects
				(font
					(size 0.7 0.7)
					(thickness 0.15)
				)
				(justify right bottom mirror)
			)
		)
		(property "Datasheet" "https://www.yageo.com/en/Chart/Download/pdf/CC0201KRX6S5BB104"
			(at 0 0 90)
			(layer "F.Fab")
			(hide yes)
			(effects
				(font
					(size 1.27 1.27)
					(thickness 0.15)
				)
			)
		)
		(property "Description" "SMD Multilayer Ceramic Capacitor, 0.1 µF, 6.3 V, 0201 [0603 Metric], ± 10%, X6S, CC Series"
			(at 0 0 90)
			(layer "F.Fab")
			(hide yes)
			(effects
				(font
					(size 1.27 1.27)
					(thickness 0.15)
				)
			)
		)
		(property "Author" "Antmicro"
			(at 218.94 -34.72 0)
			(layer "B.Fab")
			(hide yes)
			(effects
				(font
					(size 1 1)
					(thickness 0.15)
				)
				(justify mirror)
			)
		)
		(property "Dielectric" ""
			(at 218.94 -34.72 0)
			(layer "B.Fab")
			(hide yes)
			(effects
				(font
					(size 1 1)
					(thickness 0.15)
				)
				(justify mirror)
			)
		)
		(property "License" "Apache-2.0"
			(at 218.94 -34.72 0)
			(layer "B.Fab")
			(hide yes)
			(effects
				(font
					(size 1 1)
					(thickness 0.15)
				)
				(justify mirror)
			)
		)
		(property "MPN" "CC0201KRX6S5BB104"
			(at 218.94 -34.72 0)
			(layer "B.Fab")
			(hide yes)
			(effects
				(font
					(size 1 1)
					(thickness 0.15)
				)
				(justify mirror)
			)
		)
		(property "Manufacturer" "YAGEO"
			(at 218.94 -34.72 0)
			(layer "B.Fab")
			(hide yes)
			(effects
				(font
					(size 1 1)
					(thickness 0.15)
				)
				(justify mirror)
			)
		)
		(property "Val" "100n"
			(at 218.94 -34.72 0)
			(layer "B.Fab")
			(hide yes)
			(effects
				(font
					(size 1 1)
					(thickness 0.15)
				)
				(justify mirror)
			)
		)
		(property "Voltage" ""
			(at 218.94 -34.72 0)
			(layer "B.Fab")
			(hide yes)
			(effects
				(font
					(size 1 1)
					(thickness 0.15)
				)
				(justify mirror)
			)
		)
		(property "Public" "False"
			(at 0 0 90)
			(unlocked yes)
			(layer "B.Fab")
			(hide yes)
			(effects
				(font
					(size 1 1)
					(thickness 0.15)
				)
				(justify mirror)
			)
		)
		(sheetname "/FPGA Power/")
		(sheetfile "FPGA_Power.kicad_sch")
		(attr smd)
		(fp_rect
			(start -0.7 0.35)
			(end 0.7 -0.35)
			(stroke
				(width 0.05)
				(type default)
			)
			(fill no)
			(layer "B.CrtYd")
		)
		(fp_rect
			(start 0.3 -0.15)
			(end -0.301 0.149)
			(stroke
				(width 0.15)
				(type solid)
			)
			(fill no)
			(layer "B.Fab")
		)
		(fp_text user "Author: Antmicro"
			(at -0.72 -5.4 270)
			(layer "B.Fab")
			(effects
				(font
					(size 0.7 0.7)
					(thickness 0.15)
				)
				(justify left bottom mirror)
			)
		)
		(fp_text user "${REFERENCE}"
			(at -0.72 -3.4 270)
			(layer "B.Fab")
			(effects
				(font
					(size 0.7 0.7)
					(thickness 0.15)
				)
				(justify left bottom mirror)
			)
		)
		(fp_text user "License: Apache-2.0"
			(at -0.72 -4.4 270)
			(layer "B.Fab")
			(effects
				(font
					(size 0.7 0.7)
					(thickness 0.15)
				)
				(justify left bottom mirror)
			)
		)
		(pad "" smd roundrect
			(at -0.349 0.002 90)
			(size 0.318 0.36)
			(layers "B.Paste")
			(roundrect_rratio 0.25)
		)
		(pad "" smd roundrect
			(at 0.341 0.002 90)
			(size 0.318 0.36)
			(layers "B.Paste")
			(roundrect_rratio 0.25)
		)
		(pad "1" smd roundrect
			(at -0.321 0.002 90)
			(size 0.46 0.4)
			(layers "B.Cu" "B.Mask")
			(roundrect_rratio 0.25)
			(net 1 "GND")
			(pintype "passive")
		)
		(pad "2" smd roundrect
			(at 0.32 0.002 90)
			(size 0.46 0.4)
			(layers "B.Cu" "B.Mask")
			(roundrect_rratio 0.25)
			(net 9 "/FPGA Power/VCC_AUX")
			(pintype "passive")
		)
	)
	(footprint "antmicro-footprints:C_0402_1005Metric"
		(layer "B.Cu")
		(at 89.3 77.4)
		(descr "Capacitor SMD 0402")
		(tags "capacitor SMD 0402")
		(property "Reference" "C60"
			(at -1.27 -0.66 0)
			(layer "B.SilkS")
			(effects
				(font
					(size 0.65 0.65)
					(thickness 0.15)
				)
				(justify right bottom mirror)
			)
		)
		(property "Value" "C_100n_0402"
			(at 0 -1.4 0)
			(layer "B.Fab")
			(hide yes)
			(effects
				(font
					(size 0.7 0.7)
					(thickness 0.15)
				)
				(justify right bottom mirror)
			)
		)
		(property "Datasheet" "https://www.murata.com/products/productdetail?partno=GRM155R61H104KE14%23"
			(at 0 0 0)
			(layer "F.Fab")
			(hide yes)
			(effects
				(font
					(size 1.27 1.27)
					(thickness 0.15)
				)
			)
		)
		(property "Description" "SMD Multilayer Ceramic Capacitor, 0.1 µF, 50 V, 0402 [1005 Metric], ± 10%, X5R, GRM Series"
			(at 0 0 0)
			(layer "F.Fab")
			(hide yes)
			(effects
				(font
					(size 1.27 1.27)
					(thickness 0.15)
				)
			)
		)
		(property "Author" "Antmicro"
			(at 0 0 0)
			(layer "B.Fab")
			(hide yes)
			(effects
				(font
					(size 1 1)
					(thickness 0.15)
				)
				(justify mirror)
			)
		)
		(property "Dielectric" "X5R"
			(at 0 0 0)
			(layer "B.Fab")
			(hide yes)
			(effects
				(font
					(size 1 1)
					(thickness 0.15)
				)
				(justify mirror)
			)
		)
		(property "License" "Apache-2.0"
			(at 0 0 0)
			(layer "B.Fab")
			(hide yes)
			(effects
				(font
					(size 1 1)
					(thickness 0.15)
				)
				(justify mirror)
			)
		)
		(property "MPN" "GRM155R61H104KE14D"
			(at 0 0 0)
			(layer "B.Fab")
			(hide yes)
			(effects
				(font
					(size 1 1)
					(thickness 0.15)
				)
				(justify mirror)
			)
		)
		(property "Manufacturer" "Murata"
			(at 0 0 0)
			(layer "B.Fab")
			(hide yes)
			(effects
				(font
					(size 1 1)
					(thickness 0.15)
				)
				(justify mirror)
			)
		)
		(property "Val" "100n"
			(at 0 0 0)
			(layer "B.Fab")
			(hide yes)
			(effects
				(font
					(size 1 1)
					(thickness 0.15)
				)
				(justify mirror)
			)
		)
		(property "Voltage" "50V"
			(at 0 0 0)
			(layer "B.Fab")
			(hide yes)
			(effects
				(font
					(size 1 1)
					(thickness 0.15)
				)
				(justify mirror)
			)
		)
		(sheetname "/SDI/")
		(sheetfile "sdi.kicad_sch")
		(attr smd)
		(fp_rect
			(start -0.925 0.47)
			(end 0.925 -0.47)
			(stroke
				(width 0.05)
				(type default)
			)
			(fill no)
			(layer "B.CrtYd")
		)
		(fp_line
			(start -0.494 -0.248)
			(end -0.494 0.25)
			(stroke
				(width 0.15)
				(type solid)
			)
			(layer "B.Fab")
		)
		(fp_line
			(start -0.494 0.25)
			(end 0.504 0.25)
			(stroke
				(width 0.15)
				(type solid)
			)
			(layer "B.Fab")
		)
		(fp_line
			(start 0.504 -0.248)
			(end -0.494 -0.248)
			(stroke
				(width 0.15)
				(type solid)
			)
			(layer "B.Fab")
		)
		(fp_line
			(start 0.504 0.25)
			(end 0.504 -0.248)
			(stroke
				(width 0.15)
				(type solid)
			)
			(layer "B.Fab")
		)
		(fp_text user "${REFERENCE}"
			(at -0.939 -4.599 180)
			(layer "B.Fab")
			(effects
				(font
					(size 0.7 0.7)
					(thickness 0.15)
				)
				(justify left bottom mirror)
			)
		)
		(fp_text user "License: Apache-2.0"
			(at -0.939 -5.799 180)
			(layer "B.Fab")
			(effects
				(font
					(size 0.7 0.7)
					(thickness 0.15)
				)
				(justify left bottom mirror)
			)
		)
		(fp_text user "Author: Antmicro"
			(at -0.939 -3.399 180)
			(layer "B.Fab")
			(effects
				(font
					(size 0.7 0.7)
					(thickness 0.15)
				)
				(justify left bottom mirror)
			)
		)
		(pad "1" smd roundrect
			(at -0.48 0)
			(size 0.59 0.64)
			(layers "B.Cu" "B.Mask" "B.Paste")
			(roundrect_rratio 0.25)
			(net 1 "GND")
			(pintype "passive")
		)
		(pad "2" smd roundrect
			(at 0.48 0)
			(size 0.59 0.64)
			(layers "B.Cu" "B.Mask" "B.Paste")
			(roundrect_rratio 0.25)
			(net 2 "+3V3")
			(pintype "passive")
		)
	)
)
